# BASEBOARD_FAB2 (Tioga Pass) — schematic netlist excerpt (pin names and nets, part order shuffled) for the footprints in the layout excerpt that follows; sources: Cadence DE-HDL packaged netlist, KiCad conversion of Wiwynn_Tioga_Pass_MB.brd

C9W17  CAP  10UF 6.3V 20% X6S  pkg 0603  page 239 : A = P3V3_STBY ; B = GND
R12W19  RES  100.0K 1% CHIP  pkg 0603  page 197 : A = P12V_NVDIMM_KLM ; B = PWRGD_PVDDQ_KLM_N
C9P24  CAP  10UF 16V 10% X6S  pkg 0805  page 208 : A = VR_FET_SW_P12V_STBY_PVCCIN_CPU1 ; B = GND

(kicad_pcb
	(version 20260206)
	(generator "pcbnew")
	(generator_version "10.0")
	(general
		(thickness 1.6)
		(legacy_teardrops no)
	)
	(paper "A4")
	(title_block
		(title "Wiwynn_Tioga_Pass_MB.brd")
		(comment 1 "Tioga Pass / footprints 2611-2613 of 4770")
	)
	(layers
		(0 "F.Cu" signal "TOP")
		(4 "In1.Cu" signal "L2GND")
		(6 "In2.Cu" signal "L3")
		(8 "In3.Cu" signal "L4GND")
		(10 "In4.Cu" signal "L5")
		(12 "In5.Cu" signal "L6GND")
		(14 "In6.Cu" signal "L7VCC")
		(16 "In7.Cu" signal "L8VCC")
		(18 "In8.Cu" signal "L9GND")
		(20 "In9.Cu" signal "L10")
		(22 "In10.Cu" signal "L11GND")
		(24 "In11.Cu" signal "L12")
		(26 "In12.Cu" signal "L13GND")
		(2 "B.Cu" signal "BOTTOM")
		(9 "F.Adhes" user "F.Adhesive")
		(11 "B.Adhes" user "B.Adhesive")
		(13 "F.Paste" user "Package Geometry/Pastemask Top")
		(15 "B.Paste" user "Package Geometry/Pastemask Bottom")
		(5 "F.SilkS" user "Ref Des/Silkscreen Top")
		(7 "B.SilkS" user "Ref Des/Silkscreen Bottom")
		(1 "F.Mask" user "Board Geometry/Soldermask Top")
		(3 "B.Mask" user "Board Geometry/Soldermask Bottom")
		(17 "Dwgs.User" user "User.Drawings")
		(19 "Cmts.User" user "User.Comments")
		(21 "Eco1.User" user "User.Eco1")
		(23 "Eco2.User" user "User.Eco2")
		(25 "Edge.Cuts" user "Board Geometry/Outline")
		(27 "Margin" user)
		(31 "F.CrtYd" user "Package Geometry/Place Bound Top")
		(29 "B.CrtYd" user "Package Geometry/Place Bound Bottom")
		(35 "F.Fab" user "Ref Des/Assembly Top")
		(33 "B.Fab" user "Ref Des/Assembly Bottom")
	)
	(footprint ""
		(layer "B.Cu")
		(at 32.832802 -81.030064 90)
		(property "Reference" "C9P24"
			(at 0 0 90)
			(layer "B.SilkS")
			(hide yes)
			(effects
				(font
					(size 1.27 1.27)
				)
				(justify mirror)
			)
		)
		(property "Value" ""
			(at 0 0 90)
			(layer "B.Fab")
			(effects
				(font
					(size 1.27 1.27)
				)
				(justify mirror)
			)
		)
		(duplicate_pad_numbers_are_jumpers no)
		(fp_poly
			(pts
				(xy 0.7239 -0.2159) (xy -0.7239 -0.2159) (xy -0.7239 1.9939) (xy 0.7239 1.9939)
			)
			(stroke
				(width 0)
				(type default)
			)
			(fill no)
			(layer "B.CrtYd")
		)
		(fp_line
			(start 0.7239 -0.2159)
			(end 0.7239 1.9939)
			(stroke
				(width 0.1)
				(type default)
			)
			(layer "B.Fab")
		)
		(fp_line
			(start -0.7239 -0.2159)
			(end 0.7239 -0.2159)
			(stroke
				(width 0.1)
				(type default)
			)
			(layer "B.Fab")
		)
		(fp_line
			(start 0.7239 1.9939)
			(end -0.7239 1.9939)
			(stroke
				(width 0.1)
				(type default)
			)
			(layer "B.Fab")
		)
		(fp_line
			(start -0.7239 1.9939)
			(end -0.7239 -0.2159)
			(stroke
				(width 0.1)
				(type default)
			)
			(layer "B.Fab")
		)
		(pad "1" smd rect
			(at 0 0 270)
			(size 1.27 1.016)
			(layers "B.Cu" "B.Mask" "B.Paste")
			(net "VR_FET_SW_P12V_STBY_PVCCIN_CPU1")
		)
		(pad "2" smd rect
			(at 0 1.778 270)
			(size 1.27 1.016)
			(layers "B.Cu" "B.Mask" "B.Paste")
			(net "GND")
		)
		(zone
			(layer "B.Cu")
			(hatch none 0.5)
			(connect_pads
				(clearance 0)
			)
			(min_thickness 0.25)
			(keepout
				(tracks not_allowed)
				(vias allowed)
				(pads allowed)
				(copperpour not_allowed)
				(footprints allowed)
			)
			(placement
				(enabled no)
				(sheetname "")
			)
			(fill
				(thermal_gap 0.5)
				(thermal_bridge_width 0.5)
				(island_removal_mode 0)
			)
			(polygon
				(pts
					(xy 33.340802 -81.665064) (xy 33.340802 -80.395064) (xy 34.102802 -80.395064) (xy 34.102802 -81.665064)
				)
			)
		)
	)
	(footprint ""
		(layer "B.Cu")
		(at 13.0048 -124.6505 180)
		(property "Reference" "R12W19"
			(at -1.01473 0.656336 270)
			(unlocked yes)
			(layer "B.SilkS")
			(effects
				(font
					(size 0.4064 0.254)
					(thickness 0.1524)
				)
				(justify mirror)
			)
		)
		(property "Value" ""
			(at 0 0 0)
			(layer "B.Fab")
			(effects
				(font
					(size 1.27 1.27)
				)
				(justify mirror)
			)
		)
		(duplicate_pad_numbers_are_jumpers no)
		(fp_poly
			(pts
				(xy 0.4953 -0.2032) (xy -0.4953 -0.2032) (xy -0.4953 1.6002) (xy 0.4953 1.6002)
			)
			(stroke
				(width 0)
				(type default)
			)
			(fill no)
			(layer "B.CrtYd")
		)
		(fp_line
			(start 0.4953 1.6002)
			(end 0.4953 -0.2032)
			(stroke
				(width 0.1)
				(type default)
			)
			(layer "B.Fab")
		)
		(fp_line
			(start 0.4953 -0.2032)
			(end -0.4953 -0.2032)
			(stroke
				(width 0.1)
				(type default)
			)
			(layer "B.Fab")
		)
		(fp_line
			(start -0.4953 1.6002)
			(end 0.4953 1.6002)
			(stroke
				(width 0.1)
				(type default)
			)
			(layer "B.Fab")
		)
		(fp_line
			(start -0.4953 -0.2032)
			(end -0.4953 1.6002)
			(stroke
				(width 0.1)
				(type default)
			)
			(layer "B.Fab")
		)
		(pad "1" smd rect
			(at 0 0)
			(size 0.762 0.889)
			(layers "B.Cu" "B.Mask" "B.Paste")
			(net "P12V_NVDIMM_KLM")
		)
		(pad "2" smd rect
			(at 0 1.397)
			(size 0.762 0.889)
			(layers "B.Cu" "B.Mask" "B.Paste")
			(net "PWRGD_PVDDQ_KLM_N")
		)
		(zone
			(layer "B.Cu")
			(hatch none 0.5)
			(connect_pads
				(clearance 0)
			)
			(min_thickness 0.25)
			(keepout
				(tracks not_allowed)
				(vias allowed)
				(pads allowed)
				(copperpour not_allowed)
				(footprints allowed)
			)
			(placement
				(enabled no)
				(sheetname "")
			)
			(fill
				(thermal_gap 0.5)
				(thermal_bridge_width 0.5)
				(island_removal_mode 0)
			)
			(polygon
				(pts
					(xy 12.6238 -125.603) (xy 12.6238 -125.095) (xy 13.3858 -125.095) (xy 13.3858 -125.603)
				)
			)
		)
		(zone
			(layer "B.Cu")
			(hatch none 0.5)
			(connect_pads
				(clearance 0)
			)
			(min_thickness 0.25)
			(keepout
				(tracks allowed)
				(vias not_allowed)
				(pads allowed)
				(copperpour not_allowed)
				(footprints allowed)
			)
			(placement
				(enabled no)
				(sheetname "")
			)
			(fill
				(thermal_gap 0.5)
				(thermal_bridge_width 0.5)
				(island_removal_mode 0)
			)
			(polygon
				(pts
					(xy 13.3858 -125.603) (xy 13.3858 -125.095) (xy 12.6238 -125.095) (xy 12.6238 -125.603)
				)
			)
		)
	)
	(footprint ""
		(layer "B.Cu")
		(at 465.7471 -41.23182)
		(property "Reference" "C9W17"
			(at -0.97536 0.76708 90)
			(unlocked yes)
			(layer "B.SilkS")
			(effects
				(font
					(size 0.4064 0.254)
					(thickness 0.1524)
				)
				(justify mirror)
			)
		)
		(property "Value" ""
			(at 0 0 0)
			(layer "B.Fab")
			(effects
				(font
					(size 1.27 1.27)
				)
				(justify mirror)
			)
		)
		(duplicate_pad_numbers_are_jumpers no)
		(fp_poly
			(pts
				(xy 0.4953 -0.2032) (xy -0.4953 -0.2032) (xy -0.4953 1.6002) (xy 0.4953 1.6002)
			)
			(stroke
				(width 0)
				(type default)
			)
			(fill no)
			(layer "B.CrtYd")
		)
		(fp_line
			(start -0.4953 -0.2032)
			(end -0.4953 1.6002)
			(stroke
				(width 0.1)
				(type default)
			)
			(layer "B.Fab")
		)
		(fp_line
			(start -0.4953 1.6002)
			(end 0.4953 1.6002)
			(stroke
				(width 0.1)
				(type default)
			)
			(layer "B.Fab")
		)
		(fp_line
			(start 0.4953 -0.2032)
			(end -0.4953 -0.2032)
			(stroke
				(width 0.1)
				(type default)
			)
			(layer "B.Fab")
		)
		(fp_line
			(start 0.4953 1.6002)
			(end 0.4953 -0.2032)
			(stroke
				(width 0.1)
				(type default)
			)
			(layer "B.Fab")
		)
		(pad "1" smd rect
			(at 0 0 180)
			(size 0.762 0.889)
			(layers "B.Cu" "B.Mask" "B.Paste")
			(net "P3V3_STBY")
		)
		(pad "2" smd rect
			(at 0 1.397 180)
			(size 0.762 0.889)
			(layers "B.Cu" "B.Mask" "B.Paste")
			(net "GND")
		)
		(zone
			(layer "B.Cu")
			(hatch none 0.5)
			(connect_pads
				(clearance 0)
			)
			(min_thickness 0.25)
			(keepout
				(tracks not_allowed)
				(vias allowed)
				(pads allowed)
				(copperpour not_allowed)
				(footprints allowed)
			)
			(placement
				(enabled no)
				(sheetname "")
			)
			(fill
				(thermal_gap 0.5)
				(thermal_bridge_width 0.5)
				(island_removal_mode 0)
			)
			(polygon
				(pts
					(xy 466.1281 -40.78732) (xy 465.3661 -40.78732) (xy 465.3661 -40.27932) (xy 466.1281 -40.27932)
				)
			)
		)
	)
)
